(kicad_pcb
	(version 20241229)
	(generator "pcbnew")
	(generator_version "9.0")
	(general
		(thickness 1.62)
		(legacy_teardrops no)
	)
	(paper "A3")
	(title_block
		(title "COM Express 7 Baseboard")
		(date "2025-02-04")
		(rev "1.1.2")
		(company "Antmicro Ltd")
		(comment 1 "www.antmicro.com")
		(comment 9 "footprints 375-379 of 802")
	)
	(layers
		(0 "F.Cu" signal)
		(4 "In1.Cu" signal)
		(6 "In2.Cu" signal)
		(8 "In3.Cu" signal)
		(10 "In4.Cu" signal)
		(12 "In5.Cu" signal)
		(14 "In6.Cu" signal)
		(2 "B.Cu" signal)
		(9 "F.Adhes" user "F.Adhesive")
		(11 "B.Adhes" user "B.Adhesive")
		(13 "F.Paste" user)
		(15 "B.Paste" user)
		(5 "F.SilkS" user "F.Silkscreen")
		(7 "B.SilkS" user "B.Silkscreen")
		(1 "F.Mask" user)
		(3 "B.Mask" user)
		(17 "Dwgs.User" user "User.Drawings")
		(19 "Cmts.User" user "User.Comments")
		(21 "Eco1.User" user "User.Eco1")
		(23 "Eco2.User" user "User.Eco2")
		(25 "Edge.Cuts" user)
		(27 "Margin" user)
		(31 "F.CrtYd" user "F.Courtyard")
		(29 "B.CrtYd" user "B.Courtyard")
		(35 "F.Fab" user)
		(33 "B.Fab" user)
	)
	(footprint "antmicro-footprints:R_0402_1005Metric"
		(layer "F.Cu")
		(at 252.67 90.449999 180)
		(descr "Resistor SMD 0402")
		(tags "resistor SMD 0402")
		(property "Reference" "R156"
			(at 0.87 -0.440001 0)
			(layer "F.SilkS")
			(effects
				(font
					(size 0.7 0.7)
					(thickness 0.15)
				)
				(justify right bottom)
			)
		)
		(property "Value" "R_10k_0402"
			(at -1.011843 1.772047 0)
			(layer "F.Fab")
			(effects
				(font
					(size 0.7 0.7)
					(thickness 0.15)
				)
				(justify right bottom)
			)
		)
		(property "Datasheet" "https://www.bourns.com/docs/product-datasheets/cr.pdf"
			(at 0 0 180)
			(layer "F.Fab")
			(hide yes)
			(effects
				(font
					(size 1.27 1.27)
					(thickness 0.15)
				)
			)
		)
		(property "Author" "Antmicro"
			(at 505.34 180.899998 0)
			(layer "F.Fab")
			(hide yes)
			(effects
				(font
					(size 1 1)
					(thickness 0.15)
				)
			)
		)
		(property "License" "Apache-2.0"
			(at 505.34 180.899998 0)
			(layer "F.Fab")
			(hide yes)
			(effects
				(font
					(size 1 1)
					(thickness 0.15)
				)
			)
		)
		(property "MPN" "CR0402-FX-1002GLF"
			(at 505.34 180.899998 0)
			(layer "F.Fab")
			(hide yes)
			(effects
				(font
					(size 1 1)
					(thickness 0.15)
				)
			)
		)
		(property "Manufacturer" "Bourns"
			(at 505.34 180.899998 0)
			(layer "F.Fab")
			(hide yes)
			(effects
				(font
					(size 1 1)
					(thickness 0.15)
				)
			)
		)
		(property "Public" "False"
			(at 505.34 180.899998 0)
			(layer "F.Fab")
			(hide yes)
			(effects
				(font
					(size 1 1)
					(thickness 0.15)
				)
			)
		)
		(property "Tolerance" "1%"
			(at 505.34 180.899998 0)
			(layer "F.Fab")
			(hide yes)
			(effects
				(font
					(size 1 1)
					(thickness 0.15)
				)
			)
		)
		(property "Val" "10k"
			(at 505.34 180.899998 0)
			(layer "F.Fab")
			(hide yes)
			(effects
				(font
					(size 1 1)
					(thickness 0.15)
				)
			)
		)
		(sheetname "Misc")
		(sheetfile "misc.kicad_sch")
		(attr smd)
		(fp_rect
			(start -0.925 -0.47)
			(end 0.925 0.47)
			(stroke
				(width 0.05)
				(type default)
			)
			(fill no)
			(layer "F.CrtYd")
		)
		(fp_rect
			(start -0.5 -0.25)
			(end 0.5 0.25)
			(stroke
				(width 0.15)
				(type solid)
			)
			(fill no)
			(layer "F.Fab")
		)
		(pad "1" smd roundrect
			(at -0.48 0 180)
			(size 0.59 0.64)
			(layers "F.Cu" "F.Mask" "F.Paste")
			(roundrect_rratio 0.25)
			(net 597 "/Misc/PWM1")
			(pintype "passive")
			(teardrops
				(best_length_ratio 0.2)
				(max_length 1)
				(best_width_ratio 0.9)
				(max_width 2)
				(curved_edges yes)
				(filter_ratio 0.9)
				(enabled yes)
				(allow_two_segments yes)
				(prefer_zone_connections yes)
			)
		)
		(pad "2" smd roundrect
			(at 0.48 0 180)
			(size 0.59 0.64)
			(layers "F.Cu" "F.Mask" "F.Paste")
			(roundrect_rratio 0.25)
			(net 2 "+3V3")
			(pintype "passive")
			(teardrops
				(best_length_ratio 0.2)
				(max_length 1)
				(best_width_ratio 0.9)
				(max_width 2)
				(curved_edges yes)
				(filter_ratio 0.9)
				(enabled yes)
				(allow_two_segments yes)
				(prefer_zone_connections yes)
			)
		)
	)
	(footprint "antmicro-footprints:TP_SMD_0.75mm"
		(layer "F.Cu")
		(at 138.2 129.56)
		(property "Reference" "TP89"
			(at 0.45 -1.25 90)
			(layer "F.SilkS")
			(effects
				(font
					(size 0.7 0.7)
					(thickness 0.15)
				)
				(justify left bottom)
			)
		)
		(property "Value" "TP_0.75mm_SMD"
			(at 0 1.2 0)
			(layer "F.Fab")
			(effects
				(font
					(size 0.7 0.7)
					(thickness 0.15)
				)
				(justify left bottom)
			)
		)
		(property "Author" "Antmicro"
			(at 0 0 0)
			(layer "F.Fab")
			(hide yes)
			(effects
				(font
					(size 1 1)
					(thickness 0.15)
				)
			)
		)
		(property "License" "Apache-2.0"
			(at 0 0 0)
			(layer "F.Fab")
			(hide yes)
			(effects
				(font
					(size 1 1)
					(thickness 0.15)
				)
			)
		)
		(property "MPN" ""
			(at 0 0 0)
			(layer "F.Fab")
			(hide yes)
			(effects
				(font
					(size 1 1)
					(thickness 0.15)
				)
			)
		)
		(property "Manufacturer" ""
			(at 0 0 0)
			(layer "F.Fab")
			(hide yes)
			(effects
				(font
					(size 1 1)
					(thickness 0.15)
				)
			)
		)
		(property "Public" "False"
			(at 0 0 0)
			(layer "F.Fab")
			(hide yes)
			(effects
				(font
					(size 1 1)
					(thickness 0.15)
				)
			)
		)
		(sheetname "KR to SFI #2")
		(sheetfile "kr_sfi.kicad_sch")
		(attr exclude_from_pos_files exclude_from_bom)
		(fp_circle
			(center 0 0)
			(end 0.475 0)
			(stroke
				(width 0.05)
				(type default)
			)
			(fill no)
			(layer "F.CrtYd")
		)
		(pad "1" smd circle
			(at 0 0)
			(size 0.75 0.75)
			(layers "F.Cu" "F.Mask")
			(net 752 "Net-(U45C-CLKOUTB+)")
			(pinfunction "1")
			(pintype "passive")
			(teardrops
				(best_length_ratio 0.4)
				(max_length 1)
				(best_width_ratio 0.9)
				(max_width 2)
				(curved_edges yes)
				(filter_ratio 0.9)
				(enabled yes)
				(allow_two_segments yes)
				(prefer_zone_connections yes)
			)
		)
	)
	(footprint "antmicro-footprints:R_0402_1005Metric"
		(layer "F.Cu")
		(at 251.625 130.41 90)
		(descr "Resistor SMD 0402")
		(tags "resistor SMD 0402")
		(property "Reference" "R172"
			(at -5.65 0.425 270)
			(layer "F.SilkS")
			(effects
				(font
					(size 0.7 0.7)
					(thickness 0.15)
				)
				(justify left bottom)
			)
		)
		(property "Value" "R_100k_0402"
			(at -1.011843 1.772047 90)
			(layer "F.Fab")
			(effects
				(font
					(size 0.7 0.7)
					(thickness 0.15)
				)
				(justify left bottom)
			)
		)
		(property "Datasheet" "https://www.bourns.com/docs/product-datasheets/cr.pdf"
			(at 0 0 90)
			(layer "F.Fab")
			(hide yes)
			(effects
				(font
					(size 1.27 1.27)
					(thickness 0.15)
				)
			)
		)
		(property "Author" "Antmicro"
			(at 382.035 -121.215 0)
			(layer "F.Fab")
			(hide yes)
			(effects
				(font
					(size 1 1)
					(thickness 0.15)
				)
			)
		)
		(property "License" "Apache-2.0"
			(at 382.035 -121.215 0)
			(layer "F.Fab")
			(hide yes)
			(effects
				(font
					(size 1 1)
					(thickness 0.15)
				)
			)
		)
		(property "MPN" "CR0402-FX-1003GLF"
			(at 382.035 -121.215 0)
			(layer "F.Fab")
			(hide yes)
			(effects
				(font
					(size 1 1)
					(thickness 0.15)
				)
			)
		)
		(property "Manufacturer" "Bourns"
			(at 382.035 -121.215 0)
			(layer "F.Fab")
			(hide yes)
			(effects
				(font
					(size 1 1)
					(thickness 0.15)
				)
			)
		)
		(property "Public" "False"
			(at 382.035 -121.215 0)
			(layer "F.Fab")
			(hide yes)
			(effects
				(font
					(size 1 1)
					(thickness 0.15)
				)
			)
		)
		(property "Tolerance" "1%"
			(at 382.035 -121.215 0)
			(layer "F.Fab")
			(hide yes)
			(effects
				(font
					(size 1 1)
					(thickness 0.15)
				)
			)
		)
		(property "Val" "100k"
			(at 382.035 -121.215 0)
			(layer "F.Fab")
			(hide yes)
			(effects
				(font
					(size 1 1)
					(thickness 0.15)
				)
			)
		)
		(sheetname "Com Express 7 MGMT")
		(sheetfile "com_express_7_mgmt.kicad_sch")
		(attr smd)
		(fp_rect
			(start -0.925 -0.47)
			(end 0.925 0.47)
			(stroke
				(width 0.05)
				(type default)
			)
			(fill no)
			(layer "F.CrtYd")
		)
		(fp_rect
			(start -0.5 -0.25)
			(end 0.5 0.25)
			(stroke
				(width 0.15)
				(type solid)
			)
			(fill no)
			(layer "F.Fab")
		)
		(pad "1" smd roundrect
			(at -0.48 0 90)
			(size 0.59 0.64)
			(layers "F.Cu" "F.Mask" "F.Paste")
			(roundrect_rratio 0.25)
			(net 1 "GND")
			(pintype "passive")
			(teardrops
				(best_length_ratio 0.2)
				(max_length 1)
				(best_width_ratio 0.9)
				(max_width 2)
				(curved_edges yes)
				(filter_ratio 0.9)
				(enabled yes)
				(allow_two_segments yes)
				(prefer_zone_connections yes)
			)
		)
		(pad "2" smd roundrect
			(at 0.48 0 90)
			(size 0.59 0.64)
			(layers "F.Cu" "F.Mask" "F.Paste")
			(roundrect_rratio 0.25)
			(net 138 "Net-(U33-1A)")
			(pintype "passive")
			(teardrops
				(best_length_ratio 0.2)
				(max_length 1)
				(best_width_ratio 0.9)
				(max_width 2)
				(curved_edges yes)
				(filter_ratio 0.9)
				(enabled yes)
				(allow_two_segments yes)
				(prefer_zone_connections yes)
			)
		)
	)
	(footprint "antmicro-footprints:C_0402_1005Metric"
		(layer "F.Cu")
		(at 129.5 107.3 -90)
		(descr "Capacitor SMD 0402")
		(tags "capacitor SMD 0402")
		(property "Reference" "C18"
			(at -0.98 0.5 90)
			(layer "F.SilkS")
			(effects
				(font
					(size 0.7 0.7)
					(thickness 0.15)
				)
				(justify right bottom)
			)
		)
		(property "Value" "C_100n_0402"
			(at -1.022927 2.155213 90)
			(layer "F.Fab")
			(effects
				(font
					(size 0.7 0.7)
					(thickness 0.15)
				)
				(justify right bottom)
			)
		)
		(property "Datasheet" "https://www.murata.com/products/productdetail?partno=GRM155R61H104KE14%23"
			(at 0 0 270)
			(layer "F.Fab")
			(hide yes)
			(effects
				(font
					(size 1.27 1.27)
					(thickness 0.15)
				)
			)
		)
		(property "Author" "Antmicro"
			(at 22.2 236.8 0)
			(layer "F.Fab")
			(hide yes)
			(effects
				(font
					(size 1 1)
					(thickness 0.15)
				)
			)
		)
		(property "Dielectric" "X5R"
			(at 22.2 236.8 0)
			(layer "F.Fab")
			(hide yes)
			(effects
				(font
					(size 1 1)
					(thickness 0.15)
				)
			)
		)
		(property "License" "Apache-2.0"
			(at 22.2 236.8 0)
			(layer "F.Fab")
			(hide yes)
			(effects
				(font
					(size 1 1)
					(thickness 0.15)
				)
			)
		)
		(property "MPN" "GRM155R61H104KE14D"
			(at 22.2 236.8 0)
			(layer "F.Fab")
			(hide yes)
			(effects
				(font
					(size 1 1)
					(thickness 0.15)
				)
			)
		)
		(property "Manufacturer" "Murata"
			(at 22.2 236.8 0)
			(layer "F.Fab")
			(hide yes)
			(effects
				(font
					(size 1 1)
					(thickness 0.15)
				)
			)
		)
		(property "Public" "False"
			(at 22.2 236.8 0)
			(layer "F.Fab")
			(hide yes)
			(effects
				(font
					(size 1 1)
					(thickness 0.15)
				)
			)
		)
		(property "Val" "100n"
			(at 22.2 236.8 0)
			(layer "F.Fab")
			(hide yes)
			(effects
				(font
					(size 1 1)
					(thickness 0.15)
				)
			)
		)
		(property "Voltage" "50V"
			(at 22.2 236.8 0)
			(layer "F.Fab")
			(hide yes)
			(effects
				(font
					(size 1 1)
					(thickness 0.15)
				)
			)
		)
		(sheetname "2xUSB3.0+RJ45")
		(sheetfile "usb3+rj45.kicad_sch")
		(attr smd)
		(fp_rect
			(start -0.925 -0.47)
			(end 0.925 0.47)
			(stroke
				(width 0.05)
				(type default)
			)
			(fill no)
			(layer "F.CrtYd")
		)
		(fp_line
			(start -0.494 0.248)
			(end -0.494 -0.25)
			(stroke
				(width 0.15)
				(type solid)
			)
			(layer "F.Fab")
		)
		(fp_line
			(start 0.504 0.248)
			(end -0.494 0.248)
			(stroke
				(width 0.15)
				(type solid)
			)
			(layer "F.Fab")
		)
		(fp_line
			(start -0.494 -0.25)
			(end 0.504 -0.25)
			(stroke
				(width 0.15)
				(type solid)
			)
			(layer "F.Fab")
		)
		(fp_line
			(start 0.504 -0.25)
			(end 0.504 0.248)
			(stroke
				(width 0.15)
				(type solid)
			)
			(layer "F.Fab")
		)
		(pad "1" smd roundrect
			(at -0.48 0 270)
			(size 0.59 0.64)
			(layers "F.Cu" "F.Mask" "F.Paste")
			(roundrect_rratio 0.25)
			(net 51 "Net-(C13-Pad1)")
			(pintype "passive")
			(teardrops
				(best_length_ratio 0.2)
				(max_length 1)
				(best_width_ratio 0.9)
				(max_width 2)
				(curved_edges yes)
				(filter_ratio 0.9)
				(enabled yes)
				(allow_two_segments yes)
				(prefer_zone_connections yes)
			)
		)
		(pad "2" smd roundrect
			(at 0.48 0 270)
			(size 0.59 0.64)
			(layers "F.Cu" "F.Mask" "F.Paste")
			(roundrect_rratio 0.25)
			(net 1 "GND")
			(pintype "passive")
			(teardrops
				(best_length_ratio 0.2)
				(max_length 1)
				(best_width_ratio 0.9)
				(max_width 2)
				(curved_edges yes)
				(filter_ratio 0.9)
				(enabled yes)
				(allow_two_segments yes)
				(prefer_zone_connections yes)
			)
		)
	)
	(footprint "antmicro-footprints:SOT-23-8"
		(layer "F.Cu")
		(at 303.15 106.11 -90)
		(descr "http://www.ti.com/lit/ds/symlink/ina219.pdf")
		(property "Reference" "U49"
			(at -1.1 -2.7 90)
			(layer "F.SilkS")
			(effects
				(font
					(size 0.7 0.7)
					(thickness 0.15)
				)
				(justify right bottom)
			)
		)
		(property "Value" "INA219AIDCNR"
			(at 0 2.8 90)
			(layer "F.Fab")
			(effects
				(font
					(size 0.7 0.7)
					(thickness 0.15)
				)
				(justify right bottom)
			)
		)
		(property "Datasheet" "https://www.ti.com/lit/ds/symlink/ina219.pdf?ts=1713856455637&ref_url=https%253A%252F%252Fwww.mouser.es%252F"
			(at 0 0 270)
			(layer "F.Fab")
			(hide yes)
			(effects
				(font
					(size 1.27 1.27)
					(thickness 0.15)
				)
			)
		)
		(property "Author" "Antmicro"
			(at 197.04 409.26 0)
			(layer "F.Fab")
			(hide yes)
			(effects
				(font
					(size 1 1)
					(thickness 0.15)
				)
			)
		)
		(property "License" "Apache-2.0"
			(at 197.04 409.26 0)
			(layer "F.Fab")
			(hide yes)
			(effects
				(font
					(size 1 1)
					(thickness 0.15)
				)
			)
		)
		(property "MPN" "INA219AIDCNR"
			(at 197.04 409.26 0)
			(layer "F.Fab")
			(hide yes)
			(effects
				(font
					(size 1 1)
					(thickness 0.15)
				)
			)
		)
		(property "Manufacturer" "Texas Instruments"
			(at 197.04 409.26 0)
			(layer "F.Fab")
			(hide yes)
			(effects
				(font
					(size 1 1)
					(thickness 0.15)
				)
			)
		)
		(sheetname "Power")
		(sheetfile "power.kicad_sch")
		(attr smd)
		(fp_line
			(start -0.987 1.6)
			(end -0.987 1.324)
			(stroke
				(width 0.15)
				(type solid)
			)
			(layer "F.SilkS")
		)
		(fp_line
			(start -0.613 1.6)
			(end -0.987 1.6)
			(stroke
				(width 0.15)
				(type solid)
			)
			(layer "F.SilkS")
		)
		(fp_line
			(start 1 1.6)
			(end 0.6 1.6)
			(stroke
				(width 0.15)
				(type solid)
			)
			(layer "F.SilkS")
		)
		(fp_line
			(start 1 1.3)
			(end 1 1.6)
			(stroke
				(width 0.15)
				(type solid)
			)
			(layer "F.SilkS")
		)
		(fp_line
			(start -1 -1.3)
			(end -1 -1.6)
			(stroke
				(width 0.15)
				(type solid)
			)
			(layer "F.SilkS")
		)
		(fp_line
			(start 1 -1.3)
			(end 1 -1.6)
			(stroke
				(width 0.15)
				(type solid)
			)
			(layer "F.SilkS")
		)
		(fp_line
			(start -1 -1.6)
			(end -0.6 -1.6)
			(stroke
				(width 0.15)
				(type solid)
			)
			(layer "F.SilkS")
		)
		(fp_line
			(start 1 -1.6)
			(end 0.625 -1.6)
			(stroke
				(width 0.15)
				(type solid)
			)
			(layer "F.SilkS")
		)
		(fp_circle
			(center -1.3 -1.4)
			(end -1.25 -1.4)
			(stroke
				(width 0.15)
				(type solid)
			)
			(fill yes)
			(layer "F.SilkS")
		)
		(fp_rect
			(start -1.9 -1.75)
			(end 1.898 1.75)
			(stroke
				(width 0.05)
				(type solid)
			)
			(fill no)
			(layer "F.CrtYd")
		)
		(fp_line
			(start -1.4 -1.25)
			(end -1.2 -1.45)
			(stroke
				(width 0.15)
				(type solid)
			)
			(layer "F.Fab")
		)
		(fp_rect
			(start -1.401 -1.45)
			(end 1.398 1.449)
			(stroke
				(width 0.15)
				(type solid)
			)
			(fill no)
			(layer "F.Fab")
		)
		(pad "1" smd roundrect
			(at -1.3 -0.975 180)
			(size 0.45 1.1)
			(layers "F.Cu" "F.Mask" "F.Paste")
			(roundrect_rratio 0.25)
			(net 71 "Net-(U49-IN+)")
			(pinfunction "IN+")
			(pintype "passive")
			(teardrops
				(best_length_ratio 0.2)
				(max_length 1)
				(best_width_ratio 0.9)
				(max_width 2)
				(curved_edges yes)
				(filter_ratio 0.9)
				(enabled yes)
				(allow_two_segments yes)
				(prefer_zone_connections yes)
			)
		)
		(pad "2" smd roundrect
			(at -1.3 -0.325 180)
			(size 0.45 1.1)
			(layers "F.Cu" "F.Mask" "F.Paste")
			(roundrect_rratio 0.25)
			(net 2 "+3V3")
			(pinfunction "IN-")
			(pintype "passive")
			(teardrops
				(best_length_ratio 0.2)
				(max_length 1)
				(best_width_ratio 0.9)
				(max_width 2)
				(curved_edges yes)
				(filter_ratio 0.9)
				(enabled yes)
				(allow_two_segments yes)
				(prefer_zone_connections yes)
			)
		)
		(pad "3" smd roundrect
			(at -1.3 0.325 180)
			(size 0.45 1.1)
			(layers "F.Cu" "F.Mask" "F.Paste")
			(roundrect_rratio 0.25)
			(net 1 "GND")
			(pinfunction "GND")
			(pintype "power_in")
			(teardrops
				(best_length_ratio 0.2)
				(max_length 1)
				(best_width_ratio 0.9)
				(max_width 2)
				(curved_edges yes)
				(filter_ratio 0.9)
				(enabled yes)
				(allow_two_segments yes)
				(prefer_zone_connections yes)
			)
		)
		(pad "4" smd roundrect
			(at -1.3 0.975 180)
			(size 0.45 1.1)
			(layers "F.Cu" "F.Mask" "F.Paste")
			(roundrect_rratio 0.25)
			(net 73 "+3V3_AON")
			(pinfunction "V_{S}")
			(pintype "power_in")
			(teardrops
				(best_length_ratio 0.2)
				(max_length 1)
				(best_width_ratio 0.9)
				(max_width 2)
				(curved_edges yes)
				(filter_ratio 0.9)
				(enabled yes)
				(allow_two_segments yes)
				(prefer_zone_connections yes)
			)
		)
		(pad "5" smd roundrect
			(at 1.3 0.975 180)
			(size 0.45 1.1)
			(layers "F.Cu" "F.Mask" "F.Paste")
			(roundrect_rratio 0.25)
			(net 371 "/Com Express 7 MGMT/I2C.SCL")
			(pinfunction "SCL")
			(pintype "open_collector")
			(teardrops
				(best_length_ratio 0.2)
				(max_length 1)
				(best_width_ratio 0.9)
				(max_width 2)
				(curved_edges yes)
				(filter_ratio 0.9)
				(enabled yes)
				(allow_two_segments yes)
				(prefer_zone_connections yes)
			)
		)
		(pad "6" smd roundrect
			(at 1.3 0.325 180)
			(size 0.45 1.1)
			(layers "F.Cu" "F.Mask" "F.Paste")
			(roundrect_rratio 0.25)
			(net 372 "/Com Express 7 MGMT/I2C.SDA")
			(pinfunction "SDA")
			(pintype "open_collector")
			(teardrops
				(best_length_ratio 0.2)
				(max_length 1)
				(best_width_ratio 0.9)
				(max_width 2)
				(curved_edges yes)
				(filter_ratio 0.9)
				(enabled yes)
				(allow_two_segments yes)
				(prefer_zone_connections yes)
			)
		)
		(pad "7" smd roundrect
			(at 1.3 -0.325 180)
			(size 0.45 1.1)
			(layers "F.Cu" "F.Mask" "F.Paste")
			(roundrect_rratio 0.25)
			(net 73 "+3V3_AON")
			(pinfunction "A0")
			(pintype "passive")
			(teardrops
				(best_length_ratio 0.2)
				(max_length 1)
				(best_width_ratio 0.9)
				(max_width 2)
				(curved_edges yes)
				(filter_ratio 0.9)
				(enabled yes)
				(allow_two_segments yes)
				(prefer_zone_connections yes)
			)
		)
		(pad "8" smd roundrect
			(at 1.3 -0.975 180)
			(size 0.45 1.1)
			(layers "F.Cu" "F.Mask" "F.Paste")
			(roundrect_rratio 0.25)
			(net 1 "GND")
			(pinfunction "A1")
			(pintype "passive")
			(teardrops
				(best_length_ratio 0.2)
				(max_length 1)
				(best_width_ratio 0.9)
				(max_width 2)
				(curved_edges yes)
				(filter_ratio 0.9)
				(enabled yes)
				(allow_two_segments yes)
				(prefer_zone_connections yes)
			)
		)
	)
)
